(kicad_pcb
	(version 20260206)
	(generator "pcbnew")
	(generator_version "10.0")
	(general
		(thickness 1.6)
		(legacy_teardrops no)
	)
	(paper "A4")
	(title_block
		(title "Wiwynn_Tioga_Pass_MB.brd")
		(comment 1 "Tioga Pass / footprints 3573-3578 of 4770")
	)
	(layers
		(0 "F.Cu" signal "TOP")
		(4 "In1.Cu" signal "L2GND")
		(6 "In2.Cu" signal "L3")
		(8 "In3.Cu" signal "L4GND")
		(10 "In4.Cu" signal "L5")
		(12 "In5.Cu" signal "L6GND")
		(14 "In6.Cu" signal "L7VCC")
		(16 "In7.Cu" signal "L8VCC")
		(18 "In8.Cu" signal "L9GND")
		(20 "In9.Cu" signal "L10")
		(22 "In10.Cu" signal "L11GND")
		(24 "In11.Cu" signal "L12")
		(26 "In12.Cu" signal "L13GND")
		(2 "B.Cu" signal "BOTTOM")
		(9 "F.Adhes" user "F.Adhesive")
		(11 "B.Adhes" user "B.Adhesive")
		(13 "F.Paste" user "Package Geometry/Pastemask Top")
		(15 "B.Paste" user "Package Geometry/Pastemask Bottom")
		(5 "F.SilkS" user "Ref Des/Silkscreen Top")
		(7 "B.SilkS" user "Ref Des/Silkscreen Bottom")
		(1 "F.Mask" user "Board Geometry/Soldermask Top")
		(3 "B.Mask" user "Board Geometry/Soldermask Bottom")
		(17 "Dwgs.User" user "User.Drawings")
		(19 "Cmts.User" user "User.Comments")
		(21 "Eco1.User" user "User.Eco1")
		(23 "Eco2.User" user "User.Eco2")
		(25 "Edge.Cuts" user "Board Geometry/Outline")
		(27 "Margin" user)
		(31 "F.CrtYd" user "Package Geometry/Place Bound Top")
		(29 "B.CrtYd" user "Package Geometry/Place Bound Bottom")
		(35 "F.Fab" user "Ref Des/Assembly Top")
		(33 "B.Fab" user "Ref Des/Assembly Bottom")
	)
	(footprint ""
		(layer "B.Cu")
		(at 449.3895 -21.48078)
		(property "Reference" "R3W3"
			(at 0.8382 -0.67818 0)
			(unlocked yes)
			(layer "B.SilkS")
			(effects
				(font
					(size 0.4064 0.254)
					(thickness 0.1524)
				)
				(justify left mirror)
			)
		)
		(property "Value" ""
			(at 0 0 0)
			(layer "B.Fab")
			(effects
				(font
					(size 1.27 1.27)
				)
				(justify mirror)
			)
		)
		(duplicate_pad_numbers_are_jumpers no)
		(fp_poly
			(pts
				(xy 0.2794 -0.1016) (xy -0.2794 -0.1016) (xy -0.2794 0.9906) (xy 0.2794 0.9906)
			)
			(stroke
				(width 0)
				(type default)
			)
			(fill no)
			(layer "B.CrtYd")
		)
		(fp_line
			(start -0.2794 -0.1016)
			(end 0.2794 -0.1016)
			(stroke
				(width 0.1)
				(type default)
			)
			(layer "B.Fab")
		)
		(fp_line
			(start -0.2794 0.9906)
			(end -0.2794 -0.1016)
			(stroke
				(width 0.1)
				(type default)
			)
			(layer "B.Fab")
		)
		(fp_line
			(start 0.2794 -0.1016)
			(end 0.2794 0.9906)
			(stroke
				(width 0.1)
				(type default)
			)
			(layer "B.Fab")
		)
		(fp_line
			(start 0.2794 0.9906)
			(end -0.2794 0.9906)
			(stroke
				(width 0.1)
				(type default)
			)
			(layer "B.Fab")
		)
		(pad "1" smd rect
			(at 0 0 180)
			(size 0.508 0.508)
			(layers "B.Cu" "B.Mask" "B.Paste")
			(net "P3V3_STBY")
		)
		(pad "2" smd rect
			(at 0 0.889 180)
			(size 0.508 0.508)
			(layers "B.Cu" "B.Mask" "B.Paste")
			(net "FM_TPM_PRES_RST_N")
		)
		(zone
			(layer "B.Cu")
			(hatch none 0.5)
			(connect_pads
				(clearance 0)
			)
			(min_thickness 0.25)
			(keepout
				(tracks allowed)
				(vias not_allowed)
				(pads allowed)
				(copperpour not_allowed)
				(footprints allowed)
			)
			(placement
				(enabled no)
				(sheetname "")
			)
			(fill
				(thermal_gap 0.5)
				(thermal_bridge_width 0.5)
				(island_removal_mode 0)
			)
			(polygon
				(pts
					(xy 449.6435 -21.22678) (xy 449.1355 -21.22678) (xy 449.1355 -20.84578) (xy 449.6435 -20.84578)
				)
			)
		)
		(zone
			(layer "B.Cu")
			(hatch none 0.5)
			(connect_pads
				(clearance 0)
			)
			(min_thickness 0.25)
			(keepout
				(tracks not_allowed)
				(vias allowed)
				(pads allowed)
				(copperpour not_allowed)
				(footprints allowed)
			)
			(placement
				(enabled no)
				(sheetname "")
			)
			(fill
				(thermal_gap 0.5)
				(thermal_bridge_width 0.5)
				(island_removal_mode 0)
			)
			(polygon
				(pts
					(xy 449.6435 -20.84578) (xy 449.1355 -20.84578) (xy 449.1355 -21.22678) (xy 449.6435 -21.22678)
				)
			)
		)
	)
	(footprint ""
		(layer "B.Cu")
		(at 332.028038 -37.815266)
		(property "Reference" "C4T1"
			(at 0 0 0)
			(layer "B.SilkS")
			(hide yes)
			(effects
				(font
					(size 1.27 1.27)
				)
				(justify mirror)
			)
		)
		(property "Value" ""
			(at 0 0 0)
			(layer "B.Fab")
			(effects
				(font
					(size 1.27 1.27)
				)
				(justify mirror)
			)
		)
		(duplicate_pad_numbers_are_jumpers no)
		(fp_poly
			(pts
				(xy -0.3048 -0.1016) (xy -0.3048 0.9906) (xy 0.3048 0.9906) (xy 0.3048 -0.1016)
			)
			(stroke
				(width 0)
				(type default)
			)
			(fill no)
			(layer "B.CrtYd")
		)
		(fp_line
			(start -0.3048 -0.1016)
			(end 0.3048 -0.1016)
			(stroke
				(width 0.1)
				(type default)
			)
			(layer "B.Fab")
		)
		(fp_line
			(start -0.3048 0.9906)
			(end -0.3048 -0.1016)
			(stroke
				(width 0.1)
				(type default)
			)
			(layer "B.Fab")
		)
		(fp_line
			(start 0.3048 -0.1016)
			(end 0.3048 0.9906)
			(stroke
				(width 0.1)
				(type default)
			)
			(layer "B.Fab")
		)
		(fp_line
			(start 0.3048 0.9906)
			(end -0.3048 0.9906)
			(stroke
				(width 0.1)
				(type default)
			)
			(layer "B.Fab")
		)
		(pad "1" smd rect
			(at 0 0 180)
			(size 0.508 0.508)
			(layers "B.Cu" "B.Mask" "B.Paste")
			(net "P1V8_MCP_CPU0")
		)
		(pad "2" smd rect
			(at 0 0.889 180)
			(size 0.508 0.508)
			(layers "B.Cu" "B.Mask" "B.Paste")
			(net "GND")
		)
		(zone
			(layer "B.Cu")
			(hatch none 0.5)
			(connect_pads
				(clearance 0)
			)
			(min_thickness 0.25)
			(keepout
				(tracks allowed)
				(vias not_allowed)
				(pads allowed)
				(copperpour not_allowed)
				(footprints allowed)
			)
			(placement
				(enabled no)
				(sheetname "")
			)
			(fill
				(thermal_gap 0.5)
				(thermal_bridge_width 0.5)
				(island_removal_mode 0)
			)
			(polygon
				(pts
					(xy 332.282038 -37.561266) (xy 331.774038 -37.561266) (xy 331.774038 -37.180266) (xy 332.282038 -37.180266)
				)
			)
		)
		(zone
			(layer "B.Cu")
			(hatch none 0.5)
			(connect_pads
				(clearance 0)
			)
			(min_thickness 0.25)
			(keepout
				(tracks not_allowed)
				(vias allowed)
				(pads allowed)
				(copperpour not_allowed)
				(footprints allowed)
			)
			(placement
				(enabled no)
				(sheetname "")
			)
			(fill
				(thermal_gap 0.5)
				(thermal_bridge_width 0.5)
				(island_removal_mode 0)
			)
			(polygon
				(pts
					(xy 332.282038 -37.180266) (xy 331.774038 -37.180266) (xy 331.774038 -37.561266) (xy 332.282038 -37.561266)
				)
			)
		)
	)
	(footprint ""
		(layer "B.Cu")
		(at 393.2047 -10.01903 180)
		(property "Reference" "R32W11"
			(at 0.8382 -0.67818 180)
			(unlocked yes)
			(layer "B.SilkS")
			(effects
				(font
					(size 0.4064 0.254)
					(thickness 0.1524)
				)
				(justify left mirror)
			)
		)
		(property "Value" ""
			(at 0 0 0)
			(layer "B.Fab")
			(effects
				(font
					(size 1.27 1.27)
				)
				(justify mirror)
			)
		)
		(duplicate_pad_numbers_are_jumpers no)
		(fp_poly
			(pts
				(xy 0.2794 -0.1016) (xy -0.2794 -0.1016) (xy -0.2794 0.9906) (xy 0.2794 0.9906)
			)
			(stroke
				(width 0)
				(type default)
			)
			(fill no)
			(layer "B.CrtYd")
		)
		(fp_line
			(start 0.2794 0.9906)
			(end -0.2794 0.9906)
			(stroke
				(width 0.1)
				(type default)
			)
			(layer "B.Fab")
		)
		(fp_line
			(start 0.2794 -0.1016)
			(end 0.2794 0.9906)
			(stroke
				(width 0.1)
				(type default)
			)
			(layer "B.Fab")
		)
		(fp_line
			(start -0.2794 0.9906)
			(end -0.2794 -0.1016)
			(stroke
				(width 0.1)
				(type default)
			)
			(layer "B.Fab")
		)
		(fp_line
			(start -0.2794 -0.1016)
			(end 0.2794 -0.1016)
			(stroke
				(width 0.1)
				(type default)
			)
			(layer "B.Fab")
		)
		(pad "1" smd rect
			(at 0 0)
			(size 0.508 0.508)
			(layers "B.Cu" "B.Mask" "B.Paste")
			(net "SMB_M2_SDA")
		)
		(pad "2" smd rect
			(at 0 0.889)
			(size 0.508 0.508)
			(layers "B.Cu" "B.Mask" "B.Paste")
			(net "SMB_M2_SDA_R")
		)
		(zone
			(layer "B.Cu")
			(hatch none 0.5)
			(connect_pads
				(clearance 0)
			)
			(min_thickness 0.25)
			(keepout
				(tracks not_allowed)
				(vias allowed)
				(pads allowed)
				(copperpour not_allowed)
				(footprints allowed)
			)
			(placement
				(enabled no)
				(sheetname "")
			)
			(fill
				(thermal_gap 0.5)
				(thermal_bridge_width 0.5)
				(island_removal_mode 0)
			)
			(polygon
				(pts
					(xy 392.9507 -10.65403) (xy 393.4587 -10.65403) (xy 393.4587 -10.27303) (xy 392.9507 -10.27303)
				)
			)
		)
		(zone
			(layer "B.Cu")
			(hatch none 0.5)
			(connect_pads
				(clearance 0)
			)
			(min_thickness 0.25)
			(keepout
				(tracks allowed)
				(vias not_allowed)
				(pads allowed)
				(copperpour not_allowed)
				(footprints allowed)
			)
			(placement
				(enabled no)
				(sheetname "")
			)
			(fill
				(thermal_gap 0.5)
				(thermal_bridge_width 0.5)
				(island_removal_mode 0)
			)
			(polygon
				(pts
					(xy 392.9507 -10.27303) (xy 393.4587 -10.27303) (xy 393.4587 -10.65403) (xy 392.9507 -10.65403)
				)
			)
		)
	)
	(footprint ""
		(layer "B.Cu")
		(at 354.597208 -89.97188 180)
		(property "Reference" "R3N21"
			(at 0 0 0)
			(layer "B.SilkS")
			(hide yes)
			(effects
				(font
					(size 1.27 1.27)
				)
				(justify mirror)
			)
		)
		(property "Value" ""
			(at 0 0 0)
			(layer "B.Fab")
			(effects
				(font
					(size 1.27 1.27)
				)
				(justify mirror)
			)
		)
		(duplicate_pad_numbers_are_jumpers no)
		(fp_poly
			(pts
				(xy 0.2794 -0.1016) (xy -0.2794 -0.1016) (xy -0.2794 0.9906) (xy 0.2794 0.9906)
			)
			(stroke
				(width 0)
				(type default)
			)
			(fill no)
			(layer "B.CrtYd")
		)
		(fp_line
			(start 0.2794 0.9906)
			(end -0.2794 0.9906)
			(stroke
				(width 0.1)
				(type default)
			)
			(layer "B.Fab")
		)
		(fp_line
			(start 0.2794 -0.1016)
			(end 0.2794 0.9906)
			(stroke
				(width 0.1)
				(type default)
			)
			(layer "B.Fab")
		)
		(fp_line
			(start -0.2794 0.9906)
			(end -0.2794 -0.1016)
			(stroke
				(width 0.1)
				(type default)
			)
			(layer "B.Fab")
		)
		(fp_line
			(start -0.2794 -0.1016)
			(end 0.2794 -0.1016)
			(stroke
				(width 0.1)
				(type default)
			)
			(layer "B.Fab")
		)
		(pad "1" smd rect
			(at 0 0)
			(size 0.508 0.508)
			(layers "B.Cu" "B.Mask" "B.Paste")
			(net "VSENSE_PVCCIO_CPU0_AVSP")
		)
		(pad "2" smd rect
			(at 0 0.889)
			(size 0.508 0.508)
			(layers "B.Cu" "B.Mask" "B.Paste")
			(net "PVCCIO_CPU0")
		)
		(zone
			(layer "B.Cu")
			(hatch none 0.5)
			(connect_pads
				(clearance 0)
			)
			(min_thickness 0.25)
			(keepout
				(tracks not_allowed)
				(vias allowed)
				(pads allowed)
				(copperpour not_allowed)
				(footprints allowed)
			)
			(placement
				(enabled no)
				(sheetname "")
			)
			(fill
				(thermal_gap 0.5)
				(thermal_bridge_width 0.5)
				(island_removal_mode 0)
			)
			(polygon
				(pts
					(xy 354.343208 -90.60688) (xy 354.851208 -90.60688) (xy 354.851208 -90.22588) (xy 354.343208 -90.22588)
				)
			)
		)
		(zone
			(layer "B.Cu")
			(hatch none 0.5)
			(connect_pads
				(clearance 0)
			)
			(min_thickness 0.25)
			(keepout
				(tracks allowed)
				(vias not_allowed)
				(pads allowed)
				(copperpour not_allowed)
				(footprints allowed)
			)
			(placement
				(enabled no)
				(sheetname "")
			)
			(fill
				(thermal_gap 0.5)
				(thermal_bridge_width 0.5)
				(island_removal_mode 0)
			)
			(polygon
				(pts
					(xy 354.343208 -90.22588) (xy 354.851208 -90.22588) (xy 354.851208 -90.60688) (xy 354.343208 -90.60688)
				)
			)
		)
	)
	(footprint ""
		(layer "B.Cu")
		(at 382.7653 -61.5315)
		(property "Reference" "U2T1"
			(at -2.91592 -1.22809 0)
			(unlocked yes)
			(layer "B.SilkS")
			(effects
				(font
					(size 0.7874 0.5842)
					(thickness 0.1524)
				)
				(justify left mirror)
			)
		)
		(property "Value" ""
			(at 0 0 0)
			(layer "B.Fab")
			(effects
				(font
					(size 1.27 1.27)
				)
				(justify mirror)
			)
		)
		(duplicate_pad_numbers_are_jumpers no)
		(fp_line
			(start -3.9243 -0.2794)
			(end -3.9243 4.7244)
			(stroke
				(width 0.1524)
				(type default)
			)
			(layer "B.SilkS")
		)
		(fp_line
			(start -3.9243 4.7244)
			(end -1.5367 4.7244)
			(stroke
				(width 0.1524)
				(type default)
			)
			(layer "B.SilkS")
		)
		(fp_line
			(start -3.1242 -0.2794)
			(end -3.1242 0.7366)
			(stroke
				(width 0.1524)
				(type default)
			)
			(layer "B.SilkS")
		)
		(fp_line
			(start -3.1242 0.7366)
			(end -2.3622 0.7366)
			(stroke
				(width 0.1524)
				(type default)
			)
			(layer "B.SilkS")
		)
		(fp_line
			(start -2.3622 -0.2794)
			(end -3.1242 -0.2794)
			(stroke
				(width 0.1524)
				(type default)
			)
			(layer "B.SilkS")
		)
		(fp_line
			(start -2.3622 0.7366)
			(end -2.3622 -0.2794)
			(stroke
				(width 0.1524)
				(type default)
			)
			(layer "B.SilkS")
		)
		(fp_line
			(start -1.5367 -0.2794)
			(end -3.9243 -0.2794)
			(stroke
				(width 0.1524)
				(type default)
			)
			(layer "B.SilkS")
		)
		(fp_line
			(start -1.5367 4.7244)
			(end -1.5367 -0.2794)
			(stroke
				(width 0.1524)
				(type default)
			)
			(layer "B.SilkS")
		)
		(fp_circle
			(center 0.9144 -1.0414)
			(end 1.1049 -1.0414)
			(stroke
				(width 0.381)
				(type default)
			)
			(fill no)
			(layer "B.SilkS")
		)
		(fp_poly
			(pts
				(xy -0.7366 -0.2794) (xy -4.7244 -0.2794) (xy -4.7244 4.7244) (xy -0.7366 4.7244)
			)
			(stroke
				(width 0)
				(type default)
			)
			(fill no)
			(layer "B.CrtYd")
		)
		(fp_line
			(start -4.7244 -0.2794)
			(end -4.7244 4.7244)
			(stroke
				(width 0.1)
				(type default)
			)
			(layer "B.Fab")
		)
		(fp_line
			(start -4.7244 4.7244)
			(end -0.7366 4.7244)
			(stroke
				(width 0.1)
				(type default)
			)
			(layer "B.Fab")
		)
		(fp_line
			(start -0.7366 -0.2794)
			(end -4.7244 -0.2794)
			(stroke
				(width 0.1)
				(type default)
			)
			(layer "B.Fab")
		)
		(fp_line
			(start -0.7366 4.7244)
			(end -0.7366 -0.2794)
			(stroke
				(width 0.1)
				(type default)
			)
			(layer "B.Fab")
		)
		(fp_circle
			(center 0.9144 -1.0414)
			(end 1.1049 -1.0414)
			(stroke
				(width 0.381)
				(type default)
			)
			(fill no)
			(layer "B.Fab")
		)
		(pad "1" smd rect
			(at 0 0 180)
			(size 2.159 0.381)
			(layers "B.Cu" "B.Mask" "B.Paste")
			(net "FM_BIOS_SPI_BMC_CTRL")
		)
		(pad "2" smd rect
			(at 0 0.635 180)
			(size 2.159 0.381)
			(layers "B.Cu" "B.Mask" "B.Paste")
			(net "SPI_PCH_IO2_R1")
		)
		(pad "3" smd rect
			(at 0 1.27 180)
			(size 2.159 0.381)
			(layers "B.Cu" "B.Mask" "B.Paste")
			(net "TP_SPI_SWITCH1_3")
		)
		(pad "4" smd rect
			(at 0 1.905 180)
			(size 2.159 0.381)
			(layers "B.Cu" "B.Mask" "B.Paste")
			(net "SPI_BIOS_SOCKET_IO2")
		)
		(pad "5" smd rect
			(at 0 2.54 180)
			(size 2.159 0.381)
			(layers "B.Cu" "B.Mask" "B.Paste")
			(net "SPI_PCH_IO3_R1")
		)
		(pad "6" smd rect
			(at 0 3.175 180)
			(size 2.159 0.381)
			(layers "B.Cu" "B.Mask" "B.Paste")
			(net "TP_SPI_SWITCH1_6")
		)
		(pad "7" smd rect
			(at 0 3.81 180)
			(size 2.159 0.381)
			(layers "B.Cu" "B.Mask" "B.Paste")
			(net "SPI_BIOS_SOCKET_IO3")
		)
		(pad "8" smd rect
			(at 0 4.445 180)
			(size 2.159 0.381)
			(layers "B.Cu" "B.Mask" "B.Paste")
			(net "GND")
		)
		(pad "9" smd rect
			(at -5.461 4.445 180)
			(size 2.159 0.381)
			(layers "B.Cu" "B.Mask" "B.Paste")
			(net "TP_SPI_SWITCH1_9")
		)
		(pad "10" smd rect
			(at -5.461 3.81 180)
			(size 2.159 0.381)
			(layers "B.Cu" "B.Mask" "B.Paste")
			(net "TP_SPI_SWITCH1_10")
		)
		(pad "11" smd rect
			(at -5.461 3.175 180)
			(size 2.159 0.381)
			(layers "B.Cu" "B.Mask" "B.Paste")
			(net "TP_SPI_SWITCH1_11")
		)
		(pad "12" smd rect
			(at -5.461 2.54 180)
			(size 2.159 0.381)
			(layers "B.Cu" "B.Mask" "B.Paste")
			(net "TP_SPI_SWITCH1_12")
		)
		(pad "13" smd rect
			(at -5.461 1.905 180)
			(size 2.159 0.381)
			(layers "B.Cu" "B.Mask" "B.Paste")
			(net "TP_SPI_SWITCH1_13")
		)
		(pad "14" smd rect
			(at -5.461 1.27 180)
			(size 2.159 0.381)
			(layers "B.Cu" "B.Mask" "B.Paste")
			(net "TP_SPI_SWITCH1_14")
		)
		(pad "15" smd rect
			(at -5.461 0.635 180)
			(size 2.159 0.381)
			(layers "B.Cu" "B.Mask" "B.Paste")
			(net "GND")
		)
		(pad "16" smd rect
			(at -5.461 0 180)
			(size 2.159 0.381)
			(layers "B.Cu" "B.Mask" "B.Paste")
			(net "P3V3_STBY")
		)
	)
	(footprint ""
		(layer "B.Cu")
		(at 30.988 -55.7276 180)
		(property "Reference" "CT22"
			(at 0.8382 -0.84963 180)
			(unlocked yes)
			(layer "B.SilkS")
			(effects
				(font
					(size 0.7874 0.5842)
					(thickness 0.1524)
				)
				(justify left mirror)
			)
		)
		(property "Value" ""
			(at 0 0 0)
			(layer "B.Fab")
			(effects
				(font
					(size 1.27 1.27)
				)
				(justify mirror)
			)
		)
		(duplicate_pad_numbers_are_jumpers no)
		(fp_poly
			(pts
				(xy -0.3048 -0.1016) (xy -0.3048 0.9906) (xy 0.3048 0.9906) (xy 0.3048 -0.1016)
			)
			(stroke
				(width 0)
				(type default)
			)
			(fill no)
			(layer "B.CrtYd")
		)
		(fp_line
			(start 0.3048 0.9906)
			(end -0.3048 0.9906)
			(stroke
				(width 0.1)
				(type default)
			)
			(layer "B.Fab")
		)
		(fp_line
			(start 0.3048 -0.1016)
			(end 0.3048 0.9906)
			(stroke
				(width 0.1)
				(type default)
			)
			(layer "B.Fab")
		)
		(fp_line
			(start -0.3048 0.9906)
			(end -0.3048 -0.1016)
			(stroke
				(width 0.1)
				(type default)
			)
			(layer "B.Fab")
		)
		(fp_line
			(start -0.3048 -0.1016)
			(end 0.3048 -0.1016)
			(stroke
				(width 0.1)
				(type default)
			)
			(layer "B.Fab")
		)
		(pad "1" smd rect
			(at 0 0)
			(size 0.508 0.508)
			(layers "B.Cu" "B.Mask" "B.Paste")
			(net "A_TSENSE_PVCCIN_CPU1")
		)
		(pad "2" smd rect
			(at 0 0.889)
			(size 0.508 0.508)
			(layers "B.Cu" "B.Mask" "B.Paste")
			(net "GND")
		)
		(zone
			(layer "B.Cu")
			(hatch none 0.5)
			(connect_pads
				(clearance 0)
			)
			(min_thickness 0.25)
			(keepout
				(tracks not_allowed)
				(vias allowed)
				(pads allowed)
				(copperpour not_allowed)
				(footprints allowed)
			)
			(placement
				(enabled no)
				(sheetname "")
			)
			(fill
				(thermal_gap 0.5)
				(thermal_bridge_width 0.5)
				(island_removal_mode 0)
			)
			(polygon
				(pts
					(xy 30.734 -56.3626) (xy 31.242 -56.3626) (xy 31.242 -55.9816) (xy 30.734 -55.9816)
				)
			)
		)
		(zone
			(layer "B.Cu")
			(hatch none 0.5)
			(connect_pads
				(clearance 0)
			)
			(min_thickness 0.25)
			(keepout
				(tracks allowed)
				(vias not_allowed)
				(pads allowed)
				(copperpour not_allowed)
				(footprints allowed)
			)
			(placement
				(enabled no)
				(sheetname "")
			)
			(fill
				(thermal_gap 0.5)
				(thermal_bridge_width 0.5)
				(island_removal_mode 0)
			)
			(polygon
				(pts
					(xy 30.734 -55.9816) (xy 31.242 -55.9816) (xy 31.242 -56.3626) (xy 30.734 -56.3626)
				)
			)
		)
	)
)
